# S9S_MB_2U (Grand Teton) — schematic netlist excerpt (pin names and nets, part order shuffled) for the footprints in the layout excerpt that follows; sources: Cadence DE-HDL packaged netlist, KiCad conversion of 03242023_DA0F0TMBIJ0_F0T_Motherboard_J_brd_V01_OCP.brd

J4  SCONN288_ADR50017P087CC  SCONN288_ADR50017-P087CC IO  pkg DDR288S_1-1VXB  page 85
  VIN_BULK0  = P12V_S3_AUX_CPU0_NVDIMM
  RFU0  = TP_CHB_CPU0_DIMM2_FRU_0
  VIN_MGMT  = P3V3_AUX
  HSCL  = I3C_SPD_DDRABCD_CPU0_LVC1_SCL_3
  HSDA  = I3C_SPD_DDRABCD_CPU0_LVC1_SDA
  VSS0  = GND
  DQ0_A  = M_B_CPU0_SA_DQ<0>
  VSS1  = GND
  DQ1_A  = M_B_CPU0_SA_DQ<1>
  VSS2  = GND
  DQS0_A_T  = M_B_CPU0_SA_DQS_DP<0>
  DQS0_A_C  = M_B_CPU0_SA_DQS_DN<0>
  VSS3  = GND
  DQ4_A  = M_B_CPU0_SA_DQ<4>
  VSS4  = GND
  DQ5_A  = M_B_CPU0_SA_DQ<5>
  VSS5  = GND
  DQ8_A  = M_B_CPU0_SA_DQ<8>
  VSS6  = GND
  DQ9_A  = M_B_CPU0_SA_DQ<9>
  VSS7  = GND
  DQS1_A_T  = M_B_CPU0_SA_DQS_DP<1>
  DQS1_A_C  = M_B_CPU0_SA_DQS_DN<1>
  VSS8  = GND
  DQ12_A  = M_B_CPU0_SA_DQ<12>
  VSS9  = GND
  DQ13_A  = M_B_CPU0_SA_DQ<13>
  VSS10  = GND
  DQ16_A  = M_B_CPU0_SA_DQ<16>
  VSS11  = GND
  DQ17_A  = M_B_CPU0_SA_DQ<17>
  VSS12  = GND
  DQS2_A_T  = M_B_CPU0_SA_DQS_DP<2>
  DQS2_A_C  = M_B_CPU0_SA_DQS_DN<2>
  VSS13  = GND
  DQ20_A  = M_B_CPU0_SA_DQ<20>
  VSS14  = GND
  DQ21_A  = M_B_CPU0_SA_DQ<21>
  VSS15  = GND
  DQ24_A  = M_B_CPU0_SA_DQ<24>
  VSS16  = GND
  DQ25_A  = M_B_CPU0_SA_DQ<25>
  VSS17  = GND
  DQS3_A_T  = M_B_CPU0_SA_DQS_DP<3>
  DQS3_A_C  = M_B_CPU0_SA_DQS_DN<3>
  VSS18  = GND
  DQ28_A  = M_B_CPU0_SA_DQ<28>
  VSS19  = GND
  DQ29_A  = M_B_CPU0_SA_DQ<29>
  VSS20  = GND
  CB0_A  = M_B_CPU0_SA_CB<0>
  VSS21  = GND
  CB1_A  = M_B_CPU0_SA_CB<1>
  VSS22  = GND
  DQS4_A_T  = M_B_CPU0_SA_DQS_DP<4>
  DQS4_A_C  = M_B_CPU0_SA_DQS_DN<4>
  VSS23  = GND
  CB4_A  = M_B_CPU0_SA_CB<4>
  VSS24  = GND
  CB5_A  = M_B_CPU0_SA_CB<5>
  VSS25  = GND
  ALERT_N  = M_B_CPU0_ALERT_N
  VSS26  = GND
  CS0_A_N  = M_B_CPU0_SA_CS_N<2>
  VSS27  = GND
  CA0_A  = M_B_CPU0_SA_CA<0>
  VSS28  = GND
  CA2_A  = M_B_CPU0_SA_CA<2>
  VSS29  = GND
  CA4_A  = M_B_CPU0_SA_CA<4>
  VSS30  = GND
  CA6_A  = M_B_CPU0_SA_CA<6>
  VSS31  = GND
  PAR_A  = M_B_CPU0_SA_PAR
  VSS32  = GND
  CA0_B  = M_B_CPU0_SB_CA<0>
  VSS33  = GND
  CA2_B  = M_B_CPU0_SB_CA<2>
  VSS34  = GND
  CA4_B  = M_B_CPU0_SB_CA<4>
  VSS35  = GND
  CA6_B  = M_B_CPU0_SB_CA<6>
  VSS36  = GND
  CS0_B_N  = M_B_CPU0_SB_CS_N<2>
  VSS37  = GND
  \lbd||rsp_a_n\  = M_B_CPU0_SA_RSP<1>
  \lbs||rsp_b_n\  = M_B_CPU0_SB_RSP<1>
  VSS38  = GND
  CB4_B  = M_B_CPU0_SB_CB<4>
  VSS39  = GND
  CB5_B  = M_B_CPU0_SB_CB<5>
  VSS40  = GND
  \dqs9_b_t||tdqs9_b_t||dbi4_b_n\  = M_B_CPU0_SB_DQS_DP<9>
  \dqs9_b_c||tdqs9_b_c\  = M_B_CPU0_SB_DQS_DN<9>
  VSS41  = GND
  CB0_B  = M_B_CPU0_SB_CB<0>
  VSS42  = GND
  CB1_B  = M_B_CPU0_SB_CB<1>
  VSS43  = GND
  DQ0_B  = M_B_CPU0_SB_DQ<0>
  VSS44  = GND
  DQ1_B  = M_B_CPU0_SB_DQ<1>
  VSS45  = GND
  DQS0_B_T  = M_B_CPU0_SB_DQS_DP<0>
  DQS0_B_C  = M_B_CPU0_SB_DQS_DN<0>
  VSS46  = GND
  DQ4_B  = M_B_CPU0_SB_DQ<4>
  VSS47  = GND
  DQ5_B  = M_B_CPU0_SB_DQ<5>
  VSS48  = GND
  DQ8_B  = M_B_CPU0_SB_DQ<8>
  VSS49  = GND
  DQ9_B  = M_B_CPU0_SB_DQ<9>
  VSS50  = GND
  DQS1_B_T  = M_B_CPU0_SB_DQS_DP<1>
  DQS1_B_C  = M_B_CPU0_SB_DQS_DN<1>
  VSS51  = GND
  DQ12_B  = M_B_CPU0_SB_DQ<12>
  VSS52  = GND
  DQ13_B  = M_B_CPU0_SB_DQ<13>
  VSS53  = GND
  DQ16_B  = M_B_CPU0_SB_DQ<16>
  VSS54  = GND
  DQ17_B  = M_B_CPU0_SB_DQ<17>
  VSS55  = GND
  DQS2_B_T  = M_B_CPU0_SB_DQS_DP<2>
  DQS2_B_C  = M_B_CPU0_SB_DQS_DN<2>
  VSS56  = GND
  DQ20_B  = M_B_CPU0_SB_DQ<20>
  VSS57  = GND
  DQ21_B  = M_B_CPU0_SB_DQ<21>
  VSS58  = GND
  DQ24_B  = M_B_CPU0_SB_DQ<24>
  VSS59  = GND
  DQ25_B  = M_B_CPU0_SB_DQ<25>
  VSS60  = GND
  DQS3_B_T  = M_B_CPU0_SB_DQS_DP<3>
  DQS3_B_C  = M_B_CPU0_SB_DQS_DN<3>
  VSS61  = GND
  DQ28_B  = M_B_CPU0_SB_DQ<28>
  VSS62  = GND
  DQ29_B  = M_B_CPU0_SB_DQ<29>
  VSS63  = GND
  RFU1  = TP_CHB_CPU0_DIMM2_FRU_1
  VIN_BULK1  = P12V_S3_AUX_CPU0_NVDIMM
  VIN_BULK2  = P12V_S3_AUX_CPU0_NVDIMM
  \pwr_good||fail_n\  = PWRGD_CHB_CPU0_DIMM2
  HSA  = PD_CHB_CPU0_DIMM2_SAA
  RFU2  = TP_CHB_CPU0_DIMM2_FRU_2
  RFU3  = TP_CHB_CPU0_DIMM2_FRU_3
  VSS64  = GND
  DQ2_A  = M_B_CPU0_SA_DQ<2>
  VSS65  = GND
  DQ3_A  = M_B_CPU0_SA_DQ<3>
  VSS66  = GND
  \dqs5_a_c||tdqs5_a_c||dqs5_a_t||tdqs5_a_t\  = M_B_CPU0_SA_DQS_DN<5>
  \dqs5_a_t||tdqs5_a_t\  = M_B_CPU0_SA_DQS_DP<5>
  VSS67  = GND
  DQ6_A  = M_B_CPU0_SA_DQ<6>
  VSS68  = GND
  DQ7_A  = M_B_CPU0_SA_DQ<7>
  VSS69  = GND
  DQ10_A  = M_B_CPU0_SA_DQ<10>
  VSS70  = GND
  DQ11_A  = M_B_CPU0_SA_DQ<11>
  VSS71  = GND
  \dqs6_a_c||tdqs6_a_c||dqs6_a_t||tdqs6_a_t\  = M_B_CPU0_SA_DQS_DN<6>
  \dqs6_a_t||tdqs6_a_t\  = M_B_CPU0_SA_DQS_DP<6>
  VSS72  = GND
  DQ14_A  = M_B_CPU0_SA_DQ<14>
  VSS73  = GND
  DQ15_A  = M_B_CPU0_SA_DQ<15>
  VSS74  = GND
  DQ18_A  = M_B_CPU0_SA_DQ<18>
  VSS75  = GND
  DQ19_A  = M_B_CPU0_SA_DQ<19>
  VSS76  = GND
  \dqs7_a_c||tdqs7_a_c\  = M_B_CPU0_SA_DQS_DN<7>
  \dqs7_a_t||tdqs7_a_t\  = M_B_CPU0_SA_DQS_DP<7>
  VSS77  = GND
  DQ22_A  = M_B_CPU0_SA_DQ<22>
  VSS78  = GND
  DQ23_A  = M_B_CPU0_SA_DQ<23>
  VSS79  = GND
  DQ26_A  = M_B_CPU0_SA_DQ<26>
  VSS80  = GND
  DQ27_A  = M_B_CPU0_SA_DQ<27>
  VSS81  = GND
  \dqs8_a_c||tdqs8_a_c\  = M_B_CPU0_SA_DQS_DN<8>
  \dqs8_a_t||tdqs8_a_t\  = M_B_CPU0_SA_DQS_DP<8>
  VSS82  = GND
  DQ30_A  = M_B_CPU0_SA_DQ<30>
  VSS83  = GND
  DQ31_A  = M_B_CPU0_SA_DQ<31>
  VSS84  = GND
  CB2_A  = M_B_CPU0_SA_CB<2>
  VSS85  = GND
  CB3_A  = M_B_CPU0_SA_CB<3>
  VSS86  = GND
  \dqs9_a_c||tdqs9_a_c\  = M_B_CPU0_SA_DQS_DN<9>
  \dqs9_a_t||tdqs9_a_t\  = M_B_CPU0_SA_DQS_DP<9>
  VSS87  = GND
  CB6_A  = M_B_CPU0_SA_CB<6>
  VSS88  = GND
  CB7_A  = M_B_CPU0_SA_CB<7>
  VSS89  = GND
  RESET_N  = RST_M_AB_CPU0_FPGA_N
  VSS90  = GND
  CS1_A_N  = M_B_CPU0_SA_CS_N<3>
  VSS91  = GND
  CA1_A  = M_B_CPU0_SA_CA<1>
  VSS92  = GND
  CA3_A  = M_B_CPU0_SA_CA<3>
  VSS93  = GND
  CA5_A  = M_B_CPU0_SA_CA<5>
  VSS94  = GND
  CK_T  = M_B_CPU0_CLK_DP<1>
  CK_C  = M_B_CPU0_CLK_DN<1>
  VSS95  = GND
  RFU4  = TP_CHB_CPU0_DIMM2_FRU_4
  CA1_B  = M_B_CPU0_SB_CA<1>
  VSS96  = GND
  CA3_B  = M_B_CPU0_SB_CA<3>
  VSS97  = GND
  CA5_B  = M_B_CPU0_SB_CA<5>
  VSS98  = GND
  PAR_B  = M_B_CPU0_SB_PAR
  VSS99  = GND
  CS1_B_N  = M_B_CPU0_SB_CS_N<3>
  VSS100  = GND
  RFU5  = TP_CHB_CPU0_DIMM2_FRU_5
  RFU6  = TP_CHB_CPU0_DIMM2_FRU_6
  VSS101  = GND
  CB6_B  = M_B_CPU0_SB_CB<6>
  VSS102  = GND
  CB7_B  = M_B_CPU0_SB_CB<7>
  VSS103  = GND
  DQS4_B_C  = M_B_CPU0_SB_DQS_DN<4>
  DQS4_B_T  = M_B_CPU0_SB_DQS_DP<4>
  VSS104  = GND
  CB2_B  = M_B_CPU0_SB_CB<2>
  VSS105  = GND
  CB3_B  = M_B_CPU0_SB_CB<3>
  VSS106  = GND
  DQ2_B  = M_B_CPU0_SB_DQ<2>
  VSS107  = GND
  DQ3_B  = M_B_CPU0_SB_DQ<3>
  VSS108  = GND
  \dqs5_b_c||tdqs5_b_c\  = M_B_CPU0_SB_DQS_DN<5>
  \dqs5_b_t||tdqs5_b_t\  = M_B_CPU0_SB_DQS_DP<5>
  VSS109  = GND
  DQ6_B  = M_B_CPU0_SB_DQ<6>
  VSS110  = GND
  DQ7_B  = M_B_CPU0_SB_DQ<7>
  VSS111  = GND
  DQ10_B  = M_B_CPU0_SB_DQ<10>
  VSS112  = GND
  DQ11_B  = M_B_CPU0_SB_DQ<11>
  VSS113  = GND
  \dqs6_b_c||tdqs6_b_c\  = M_B_CPU0_SB_DQS_DN<6>
  \dqs6_b_t||tdqs6_b_t\  = M_B_CPU0_SB_DQS_DP<6>
  VSS114  = GND
  DQ14_B  = M_B_CPU0_SB_DQ<14>
  VSS115  = GND
  DQ15_B  = M_B_CPU0_SB_DQ<15>
  VSS116  = GND
  DQ18_B  = M_B_CPU0_SB_DQ<18>
  VSS117  = GND
  DQ19_B  = M_B_CPU0_SB_DQ<19>
  VSS118  = GND
  \dqs7_b_c||tdqs7_b_c\  = M_B_CPU0_SB_DQS_DN<7>
  \dqs7_b_t||tdqs7_b_t\  = M_B_CPU0_SB_DQS_DP<7>
  VSS119  = GND
  DQ22_B  = M_B_CPU0_SB_DQ<22>
  VSS120  = GND
  DQ23_B  = M_B_CPU0_SB_DQ<23>
  VSS121  = GND
  DQ26_B  = M_B_CPU0_SB_DQ<26>
  VSS122  = GND
  DQ27_B  = M_B_CPU0_SB_DQ<27>
  VSS123  = GND
  \dqs8_b_c||tdqs8_b_c\  = M_B_CPU0_SB_DQS_DN<8>
  \dqs8_b_t||tdqs8_b_t\  = M_B_CPU0_SB_DQS_DP<8>
  VSS124  = GND
  DQ30_B  = M_B_CPU0_SB_DQ<30>
  VSS125  = GND
  DQ31_B  = M_B_CPU0_SB_DQ<31>
  VSS126  = GND
  G1  = GND
  G2  = GND
  G3  = GND

(kicad_pcb
	(version 20260206)
	(generator "pcbnew")
	(generator_version "10.0")
	(general
		(thickness 1.6)
		(legacy_teardrops no)
	)
	(paper "A4")
	(title_block
		(title "03242023_DA0F0TMBIJ0_F0T_Motherboard_J_brd_V01_OCP.brd")
		(comment 1 "Grand Teton / footprint 1229 of 6105 (J4), pads 1-45 of 291")
	)
	(layers
		(0 "F.Cu" signal "TOP")
		(4 "In1.Cu" signal "GND")
		(6 "In2.Cu" signal "IN1")
		(8 "In3.Cu" signal "GND1")
		(10 "In4.Cu" signal "IN2")
		(12 "In5.Cu" signal "GND2")
		(14 "In6.Cu" signal "IN3")
		(16 "In7.Cu" signal "GND3")
		(18 "In8.Cu" signal "VCC")
		(20 "In9.Cu" signal "VCC1")
		(22 "In10.Cu" signal "GND4")
		(24 "In11.Cu" signal "IN4")
		(26 "In12.Cu" signal "GND5")
		(28 "In13.Cu" signal "IN5")
		(30 "In14.Cu" signal "GND6")
		(32 "In15.Cu" signal "IN6")
		(34 "In16.Cu" signal "GND7")
		(2 "B.Cu" signal "BOTTOM")
		(9 "F.Adhes" user "F.Adhesive")
		(11 "B.Adhes" user "B.Adhesive")
		(13 "F.Paste" user "Package Geometry/Pastemask Top")
		(15 "B.Paste" user "Package Geometry/Pastemask Bottom")
		(5 "F.SilkS" user "Ref Des/Silkscreen Top")
		(7 "B.SilkS" user "Ref Des/Silkscreen Bottom")
		(1 "F.Mask" user "Board Geometry/Soldermask Top")
		(3 "B.Mask" user "Board Geometry/Soldermask Bottom")
		(17 "Dwgs.User" user "User.Drawings")
		(19 "Cmts.User" user "User.Comments")
		(21 "Eco1.User" user "User.Eco1")
		(23 "Eco2.User" user "User.Eco2")
		(25 "Edge.Cuts" user "Board Geometry/Outline")
		(27 "Margin" user)
		(31 "F.CrtYd" user "Package Geometry/Place Bound Top")
		(29 "B.CrtYd" user "Package Geometry/Place Bound Bottom")
		(35 "F.Fab" user "Ref Des/Assembly Top")
		(33 "B.Fab" user "Ref Des/Assembly Bottom")
	)
	(footprint ""
		(layer "F.Cu")
		(at 295.849548 -258.091686)
		(property "Reference" "J4"
			(at -3.683 -81.702148 0)
			(unlocked yes)
			(layer "F.SilkS")
			(effects
				(font
					(size 0.7874 0.5842)
					(thickness 0.1524)
				)
				(justify left)
			)
		)
		(property "Value" ""
			(at 0 0 0)
			(layer "F.Fab")
			(effects
				(font
					(size 1.27 1.27)
				)
			)
		)
		(duplicate_pad_numbers_are_jumpers no)
		(pad "1" smd rect
			(at -2.050034 -63.324994 270)
			(size 0.519938 1.4986)
			(layers "F.Cu" "F.Mask" "F.Paste")
			(net "P12V_S3_AUX_CPU0_NVDIMM")
		)
		(pad "2" smd rect
			(at -2.050034 -62.47511 270)
			(size 0.519938 1.4986)
			(layers "F.Cu" "F.Mask" "F.Paste")
			(net "TP_CHB_CPU0_DIMM2_FRU_0")
		)
		(pad "3" smd rect
			(at -2.050034 -61.624972 270)
			(size 0.519938 1.4986)
			(layers "F.Cu" "F.Mask" "F.Paste")
			(net "P3V3_AUX")
		)
		(pad "4" smd rect
			(at -2.050034 -60.775088 270)
			(size 0.519938 1.4986)
			(layers "F.Cu" "F.Mask" "F.Paste")
			(net "I3C_SPD_DDRABCD_CPU0_LVC1_SCL_3")
		)
		(pad "5" smd rect
			(at -2.050034 -59.92495 270)
			(size 0.519938 1.4986)
			(layers "F.Cu" "F.Mask" "F.Paste")
			(net "I3C_SPD_DDRABCD_CPU0_LVC1_SDA")
		)
		(pad "6" smd rect
			(at -2.050034 -59.075066 270)
			(size 0.519938 1.4986)
			(layers "F.Cu" "F.Mask" "F.Paste")
			(net "GND")
		)
		(pad "7" smd rect
			(at -2.050034 -58.224928 270)
			(size 0.519938 1.4986)
			(layers "F.Cu" "F.Mask" "F.Paste")
			(net "M_B_CPU0_SA_DQ<0>")
		)
		(pad "8" smd rect
			(at -2.050034 -57.375044 270)
			(size 0.519938 1.4986)
			(layers "F.Cu" "F.Mask" "F.Paste")
			(net "GND")
		)
		(pad "9" smd rect
			(at -2.050034 -56.524906 270)
			(size 0.519938 1.4986)
			(layers "F.Cu" "F.Mask" "F.Paste")
			(net "M_B_CPU0_SA_DQ<1>")
		)
		(pad "10" smd rect
			(at -2.050034 -55.675022 270)
			(size 0.519938 1.4986)
			(layers "F.Cu" "F.Mask" "F.Paste")
			(net "GND")
		)
		(pad "11" smd rect
			(at -2.050034 -54.824884 270)
			(size 0.519938 1.4986)
			(layers "F.Cu" "F.Mask" "F.Paste")
			(net "M_B_CPU0_SA_DQS_DP<0>")
		)
		(pad "12" smd rect
			(at -2.050034 -53.975 270)
			(size 0.519938 1.4986)
			(layers "F.Cu" "F.Mask" "F.Paste")
			(net "M_B_CPU0_SA_DQS_DN<0>")
		)
		(pad "13" smd rect
			(at -2.050034 -53.125116 270)
			(size 0.519938 1.4986)
			(layers "F.Cu" "F.Mask" "F.Paste")
			(net "GND")
		)
		(pad "14" smd rect
			(at -2.050034 -52.274978 270)
			(size 0.519938 1.4986)
			(layers "F.Cu" "F.Mask" "F.Paste")
			(net "M_B_CPU0_SA_DQ<4>")
		)
		(pad "15" smd rect
			(at -2.050034 -51.425094 270)
			(size 0.519938 1.4986)
			(layers "F.Cu" "F.Mask" "F.Paste")
			(net "GND")
		)
		(pad "16" smd rect
			(at -2.050034 -50.574956 270)
			(size 0.519938 1.4986)
			(layers "F.Cu" "F.Mask" "F.Paste")
			(net "M_B_CPU0_SA_DQ<5>")
		)
		(pad "17" smd rect
			(at -2.050034 -49.725072 270)
			(size 0.519938 1.4986)
			(layers "F.Cu" "F.Mask" "F.Paste")
			(net "GND")
		)
		(pad "18" smd rect
			(at -2.050034 -48.874934 270)
			(size 0.519938 1.4986)
			(layers "F.Cu" "F.Mask" "F.Paste")
			(net "M_B_CPU0_SA_DQ<8>")
		)
		(pad "19" smd rect
			(at -2.050034 -48.02505 270)
			(size 0.519938 1.4986)
			(layers "F.Cu" "F.Mask" "F.Paste")
			(net "GND")
		)
		(pad "20" smd rect
			(at -2.050034 -47.174912 270)
			(size 0.519938 1.4986)
			(layers "F.Cu" "F.Mask" "F.Paste")
			(net "M_B_CPU0_SA_DQ<9>")
		)
		(pad "21" smd rect
			(at -2.050034 -46.325028 270)
			(size 0.519938 1.4986)
			(layers "F.Cu" "F.Mask" "F.Paste")
			(net "GND")
		)
		(pad "22" smd rect
			(at -2.050034 -45.47489 270)
			(size 0.519938 1.4986)
			(layers "F.Cu" "F.Mask" "F.Paste")
			(net "M_B_CPU0_SA_DQS_DP<1>")
		)
		(pad "23" smd rect
			(at -2.050034 -44.625006 270)
			(size 0.519938 1.4986)
			(layers "F.Cu" "F.Mask" "F.Paste")
			(net "M_B_CPU0_SA_DQS_DN<1>")
		)
		(pad "24" smd rect
			(at -2.050034 -43.775122 270)
			(size 0.519938 1.4986)
			(layers "F.Cu" "F.Mask" "F.Paste")
			(net "GND")
		)
		(pad "25" smd rect
			(at -2.050034 -42.924984 270)
			(size 0.519938 1.4986)
			(layers "F.Cu" "F.Mask" "F.Paste")
			(net "M_B_CPU0_SA_DQ<12>")
		)
		(pad "26" smd rect
			(at -2.050034 -42.0751 270)
			(size 0.519938 1.4986)
			(layers "F.Cu" "F.Mask" "F.Paste")
			(net "GND")
		)
		(pad "27" smd rect
			(at -2.050034 -41.224962 270)
			(size 0.519938 1.4986)
			(layers "F.Cu" "F.Mask" "F.Paste")
			(net "M_B_CPU0_SA_DQ<13>")
		)
		(pad "28" smd rect
			(at -2.050034 -40.375078 270)
			(size 0.519938 1.4986)
			(layers "F.Cu" "F.Mask" "F.Paste")
			(net "GND")
		)
		(pad "29" smd rect
			(at -2.050034 -39.52494 270)
			(size 0.519938 1.4986)
			(layers "F.Cu" "F.Mask" "F.Paste")
			(net "M_B_CPU0_SA_DQ<16>")
		)
		(pad "30" smd rect
			(at -2.050034 -38.675056 270)
			(size 0.519938 1.4986)
			(layers "F.Cu" "F.Mask" "F.Paste")
			(net "GND")
		)
		(pad "31" smd rect
			(at -2.050034 -37.824918 270)
			(size 0.519938 1.4986)
			(layers "F.Cu" "F.Mask" "F.Paste")
			(net "M_B_CPU0_SA_DQ<17>")
		)
		(pad "32" smd rect
			(at -2.050034 -36.975034 270)
			(size 0.519938 1.4986)
			(layers "F.Cu" "F.Mask" "F.Paste")
			(net "GND")
		)
		(pad "33" smd rect
			(at -2.050034 -36.124896 270)
			(size 0.519938 1.4986)
			(layers "F.Cu" "F.Mask" "F.Paste")
			(net "M_B_CPU0_SA_DQS_DP<2>")
		)
		(pad "34" smd rect
			(at -2.050034 -35.275012 270)
			(size 0.519938 1.4986)
			(layers "F.Cu" "F.Mask" "F.Paste")
			(net "M_B_CPU0_SA_DQS_DN<2>")
		)
		(pad "35" smd rect
			(at -2.050034 -34.425128 270)
			(size 0.519938 1.4986)
			(layers "F.Cu" "F.Mask" "F.Paste")
			(net "GND")
		)
		(pad "36" smd rect
			(at -2.050034 -33.57499 270)
			(size 0.519938 1.4986)
			(layers "F.Cu" "F.Mask" "F.Paste")
			(net "M_B_CPU0_SA_DQ<20>")
		)
		(pad "37" smd rect
			(at -2.050034 -32.725106 270)
			(size 0.519938 1.4986)
			(layers "F.Cu" "F.Mask" "F.Paste")
			(net "GND")
		)
		(pad "38" smd rect
			(at -2.050034 -31.874968 270)
			(size 0.519938 1.4986)
			(layers "F.Cu" "F.Mask" "F.Paste")
			(net "M_B_CPU0_SA_DQ<21>")
		)
		(pad "39" smd rect
			(at -2.050034 -31.025084 270)
			(size 0.519938 1.4986)
			(layers "F.Cu" "F.Mask" "F.Paste")
			(net "GND")
		)
		(pad "40" smd rect
			(at -2.050034 -30.174946 270)
			(size 0.519938 1.4986)
			(layers "F.Cu" "F.Mask" "F.Paste")
			(net "M_B_CPU0_SA_DQ<24>")
		)
		(pad "41" smd rect
			(at -2.050034 -29.325062 270)
			(size 0.519938 1.4986)
			(layers "F.Cu" "F.Mask" "F.Paste")
			(net "GND")
		)
		(pad "42" smd rect
			(at -2.050034 -28.474924 270)
			(size 0.519938 1.4986)
			(layers "F.Cu" "F.Mask" "F.Paste")
			(net "M_B_CPU0_SA_DQ<25>")
		)
		(pad "43" smd rect
			(at -2.050034 -27.62504 270)
			(size 0.519938 1.4986)
			(layers "F.Cu" "F.Mask" "F.Paste")
			(net "GND")
		)
		(pad "44" smd rect
			(at -2.050034 -26.774902 270)
			(size 0.519938 1.4986)
			(layers "F.Cu" "F.Mask" "F.Paste")
			(net "M_B_CPU0_SA_DQS_DP<3>")
		)
		(pad "45" smd rect
			(at -2.050034 -25.925018 270)
			(size 0.519938 1.4986)
			(layers "F.Cu" "F.Mask" "F.Paste")
			(net "M_B_CPU0_SA_DQS_DN<3>")
		)
	)
)
